(kicad_pcb
	(version 20260206)
	(generator "pcbnew")
	(generator_version "10.0")
	(general
		(thickness 1.6)
		(legacy_teardrops no)
	)
	(paper "A4")
	(title_block
		(title "9052_F0T_PDB_Converter_Brick_F_V03_1208_1600_OCP.brd")
		(comment 1 "Grand Teton / footprints 394-399 of 578")
	)
	(layers
		(0 "F.Cu" signal "TOP")
		(4 "In1.Cu" signal "GND")
		(6 "In2.Cu" signal "IN1")
		(8 "In3.Cu" signal "GND1")
		(10 "In4.Cu" signal "VCC")
		(12 "In5.Cu" signal "VCC1")
		(14 "In6.Cu" signal "GND2")
		(16 "In7.Cu" signal "IN2")
		(18 "In8.Cu" signal "GND3")
		(2 "B.Cu" signal "BOTTOM")
		(9 "F.Adhes" user "F.Adhesive")
		(11 "B.Adhes" user "B.Adhesive")
		(13 "F.Paste" user "Package Geometry/Pastemask Top")
		(15 "B.Paste" user "Package Geometry/Pastemask Bottom")
		(5 "F.SilkS" user "Ref Des/Silkscreen Top")
		(7 "B.SilkS" user "Ref Des/Silkscreen Bottom")
		(1 "F.Mask" user "Board Geometry/Soldermask Top")
		(3 "B.Mask" user "Board Geometry/Soldermask Bottom")
		(17 "Dwgs.User" user "User.Drawings")
		(19 "Cmts.User" user "User.Comments")
		(21 "Eco1.User" user "User.Eco1")
		(23 "Eco2.User" user "User.Eco2")
		(25 "Edge.Cuts" user "Board Geometry/Outline")
		(27 "Margin" user)
		(31 "F.CrtYd" user "Package Geometry/Place Bound Top")
		(29 "B.CrtYd" user "Package Geometry/Place Bound Bottom")
		(35 "F.Fab" user "Ref Des/Assembly Top")
		(33 "B.Fab" user "Ref Des/Assembly Bottom")
	)
	(footprint ""
		(layer "B.Cu")
		(at 58.928 -77.47 180)
		(property "Reference" "C63"
			(at 0 0 0)
			(layer "B.SilkS")
			(hide yes)
			(effects
				(font
					(size 1.27 1.27)
				)
				(justify mirror)
			)
		)
		(property "Value" ""
			(at 0 0 0)
			(layer "B.Fab")
			(effects
				(font
					(size 1.27 1.27)
				)
				(justify mirror)
			)
		)
		(duplicate_pad_numbers_are_jumpers no)
		(fp_line
			(start 0.7874 0.4064)
			(end 0.7874 -0.4064)
			(stroke
				(width 0.1524)
				(type default)
			)
			(layer "B.SilkS")
		)
		(fp_line
			(start 0.7874 -0.4064)
			(end -0.7874 -0.4064)
			(stroke
				(width 0.1524)
				(type default)
			)
			(layer "B.SilkS")
		)
		(fp_line
			(start -0.7874 0.4064)
			(end 0.7874 0.4064)
			(stroke
				(width 0.1524)
				(type default)
			)
			(layer "B.SilkS")
		)
		(fp_line
			(start -0.7874 -0.4064)
			(end -0.7874 0.4064)
			(stroke
				(width 0.1524)
				(type default)
			)
			(layer "B.SilkS")
		)
		(fp_line
			(start 0.67945 0.3048)
			(end 0.67945 -0.305054)
			(stroke
				(width 0.1)
				(type default)
			)
			(layer "B.Fab")
		)
		(fp_line
			(start 0.67945 -0.305054)
			(end 0.12065 -0.305054)
			(stroke
				(width 0.1)
				(type default)
			)
			(layer "B.Fab")
		)
		(fp_line
			(start 0.12065 0.3048)
			(end 0.67945 0.3048)
			(stroke
				(width 0.1)
				(type default)
			)
			(layer "B.Fab")
		)
		(fp_line
			(start 0.12065 0.2794)
			(end 0.12065 0.3048)
			(stroke
				(width 0.1)
				(type default)
			)
			(layer "B.Fab")
		)
		(fp_line
			(start 0.12065 -0.2794)
			(end -0.12065 -0.2794)
			(stroke
				(width 0.1)
				(type default)
			)
			(layer "B.Fab")
		)
		(fp_line
			(start 0.12065 -0.305054)
			(end 0.12065 -0.2794)
			(stroke
				(width 0.1)
				(type default)
			)
			(layer "B.Fab")
		)
		(fp_line
			(start -0.120396 0.3048)
			(end -0.120396 0.2794)
			(stroke
				(width 0.1)
				(type default)
			)
			(layer "B.Fab")
		)
		(fp_line
			(start -0.120396 0.2794)
			(end 0.12065 0.2794)
			(stroke
				(width 0.1)
				(type default)
			)
			(layer "B.Fab")
		)
		(fp_line
			(start -0.12065 -0.2794)
			(end -0.12065 -0.3048)
			(stroke
				(width 0.1)
				(type default)
			)
			(layer "B.Fab")
		)
		(fp_line
			(start -0.12065 -0.3048)
			(end -0.67945 -0.3048)
			(stroke
				(width 0.1)
				(type default)
			)
			(layer "B.Fab")
		)
		(fp_line
			(start -0.67945 0.3048)
			(end -0.120396 0.3048)
			(stroke
				(width 0.1)
				(type default)
			)
			(layer "B.Fab")
		)
		(fp_line
			(start -0.67945 -0.3048)
			(end -0.67945 0.3048)
			(stroke
				(width 0.1)
				(type default)
			)
			(layer "B.Fab")
		)
		(pad "1" smd circle
			(at 0.40005 0)
			(size 0 0)
			(layers "B.Cu" "B.Mask" "B.Paste")
			(net "SMB_P52V_VPDB_SCL")
		)
		(pad "2" smd circle
			(at -0.40005 0)
			(size 0 0)
			(layers "B.Cu" "B.Mask" "B.Paste")
			(net "GND")
		)
	)
	(footprint ""
		(layer "B.Cu")
		(at 238.506 -77.851 180)
		(property "Reference" "R5"
			(at 0 0 0)
			(layer "B.SilkS")
			(hide yes)
			(effects
				(font
					(size 1.27 1.27)
				)
				(justify mirror)
			)
		)
		(property "Value" ""
			(at 0 0 0)
			(layer "B.Fab")
			(effects
				(font
					(size 1.27 1.27)
				)
				(justify mirror)
			)
		)
		(duplicate_pad_numbers_are_jumpers no)
		(fp_line
			(start 0.7874 0.4064)
			(end 0.7874 -0.4064)
			(stroke
				(width 0.1524)
				(type default)
			)
			(layer "B.SilkS")
		)
		(fp_line
			(start 0.7874 -0.4064)
			(end -0.7874 -0.4064)
			(stroke
				(width 0.1524)
				(type default)
			)
			(layer "B.SilkS")
		)
		(fp_line
			(start -0.7874 0.4064)
			(end 0.7874 0.4064)
			(stroke
				(width 0.1524)
				(type default)
			)
			(layer "B.SilkS")
		)
		(fp_line
			(start -0.7874 -0.4064)
			(end -0.7874 0.4064)
			(stroke
				(width 0.1524)
				(type default)
			)
			(layer "B.SilkS")
		)
		(fp_line
			(start 0.67945 0.3048)
			(end 0.67945 -0.305054)
			(stroke
				(width 0.1)
				(type default)
			)
			(layer "B.Fab")
		)
		(fp_line
			(start 0.67945 -0.305054)
			(end 0.12065 -0.305054)
			(stroke
				(width 0.1)
				(type default)
			)
			(layer "B.Fab")
		)
		(fp_line
			(start 0.12065 0.3048)
			(end 0.67945 0.3048)
			(stroke
				(width 0.1)
				(type default)
			)
			(layer "B.Fab")
		)
		(fp_line
			(start 0.12065 0.2794)
			(end 0.12065 0.3048)
			(stroke
				(width 0.1)
				(type default)
			)
			(layer "B.Fab")
		)
		(fp_line
			(start 0.12065 -0.2794)
			(end -0.12065 -0.2794)
			(stroke
				(width 0.1)
				(type default)
			)
			(layer "B.Fab")
		)
		(fp_line
			(start 0.12065 -0.305054)
			(end 0.12065 -0.2794)
			(stroke
				(width 0.1)
				(type default)
			)
			(layer "B.Fab")
		)
		(fp_line
			(start -0.120396 0.3048)
			(end -0.120396 0.2794)
			(stroke
				(width 0.1)
				(type default)
			)
			(layer "B.Fab")
		)
		(fp_line
			(start -0.120396 0.2794)
			(end 0.12065 0.2794)
			(stroke
				(width 0.1)
				(type default)
			)
			(layer "B.Fab")
		)
		(fp_line
			(start -0.12065 -0.2794)
			(end -0.12065 -0.3048)
			(stroke
				(width 0.1)
				(type default)
			)
			(layer "B.Fab")
		)
		(fp_line
			(start -0.12065 -0.3048)
			(end -0.67945 -0.3048)
			(stroke
				(width 0.1)
				(type default)
			)
			(layer "B.Fab")
		)
		(fp_line
			(start -0.67945 0.3048)
			(end -0.120396 0.3048)
			(stroke
				(width 0.1)
				(type default)
			)
			(layer "B.Fab")
		)
		(fp_line
			(start -0.67945 -0.3048)
			(end -0.67945 0.3048)
			(stroke
				(width 0.1)
				(type default)
			)
			(layer "B.Fab")
		)
		(pad "1" smd circle
			(at 0.40005 0)
			(size 0 0)
			(layers "B.Cu" "B.Mask" "B.Paste")
			(net "SMB_PDB_MISC_SDA_R")
		)
		(pad "2" smd circle
			(at -0.40005 0)
			(size 0 0)
			(layers "B.Cu" "B.Mask" "B.Paste")
			(net "SMB_PDB_MISC_SDA")
		)
	)
	(footprint ""
		(layer "B.Cu")
		(at 94.361 -76.327 180)
		(property "Reference" "R172"
			(at 0 0 0)
			(layer "B.SilkS")
			(hide yes)
			(effects
				(font
					(size 1.27 1.27)
				)
				(justify mirror)
			)
		)
		(property "Value" ""
			(at 0 0 0)
			(layer "B.Fab")
			(effects
				(font
					(size 1.27 1.27)
				)
				(justify mirror)
			)
		)
		(duplicate_pad_numbers_are_jumpers no)
		(fp_line
			(start 0.7874 0.4064)
			(end 0.7874 -0.4064)
			(stroke
				(width 0.1524)
				(type default)
			)
			(layer "B.SilkS")
		)
		(fp_line
			(start 0.7874 -0.4064)
			(end -0.7874 -0.4064)
			(stroke
				(width 0.1524)
				(type default)
			)
			(layer "B.SilkS")
		)
		(fp_line
			(start -0.7874 0.4064)
			(end 0.7874 0.4064)
			(stroke
				(width 0.1524)
				(type default)
			)
			(layer "B.SilkS")
		)
		(fp_line
			(start -0.7874 -0.4064)
			(end -0.7874 0.4064)
			(stroke
				(width 0.1524)
				(type default)
			)
			(layer "B.SilkS")
		)
		(fp_line
			(start 0.67945 0.3048)
			(end 0.67945 -0.305054)
			(stroke
				(width 0.1)
				(type default)
			)
			(layer "B.Fab")
		)
		(fp_line
			(start 0.67945 -0.305054)
			(end 0.12065 -0.305054)
			(stroke
				(width 0.1)
				(type default)
			)
			(layer "B.Fab")
		)
		(fp_line
			(start 0.12065 0.3048)
			(end 0.67945 0.3048)
			(stroke
				(width 0.1)
				(type default)
			)
			(layer "B.Fab")
		)
		(fp_line
			(start 0.12065 0.2794)
			(end 0.12065 0.3048)
			(stroke
				(width 0.1)
				(type default)
			)
			(layer "B.Fab")
		)
		(fp_line
			(start 0.12065 -0.2794)
			(end -0.12065 -0.2794)
			(stroke
				(width 0.1)
				(type default)
			)
			(layer "B.Fab")
		)
		(fp_line
			(start 0.12065 -0.305054)
			(end 0.12065 -0.2794)
			(stroke
				(width 0.1)
				(type default)
			)
			(layer "B.Fab")
		)
		(fp_line
			(start -0.120396 0.3048)
			(end -0.120396 0.2794)
			(stroke
				(width 0.1)
				(type default)
			)
			(layer "B.Fab")
		)
		(fp_line
			(start -0.120396 0.2794)
			(end 0.12065 0.2794)
			(stroke
				(width 0.1)
				(type default)
			)
			(layer "B.Fab")
		)
		(fp_line
			(start -0.12065 -0.2794)
			(end -0.12065 -0.3048)
			(stroke
				(width 0.1)
				(type default)
			)
			(layer "B.Fab")
		)
		(fp_line
			(start -0.12065 -0.3048)
			(end -0.67945 -0.3048)
			(stroke
				(width 0.1)
				(type default)
			)
			(layer "B.Fab")
		)
		(fp_line
			(start -0.67945 0.3048)
			(end -0.120396 0.3048)
			(stroke
				(width 0.1)
				(type default)
			)
			(layer "B.Fab")
		)
		(fp_line
			(start -0.67945 -0.3048)
			(end -0.67945 0.3048)
			(stroke
				(width 0.1)
				(type default)
			)
			(layer "B.Fab")
		)
		(pad "1" smd circle
			(at 0.40005 0)
			(size 0 0)
			(layers "B.Cu" "B.Mask" "B.Paste")
			(net "P12V_BRICK1_ALERT_N")
		)
		(pad "2" smd circle
			(at -0.40005 0)
			(size 0 0)
			(layers "B.Cu" "B.Mask" "B.Paste")
			(net "SMB_BRICK1_ALERT")
		)
	)
	(footprint ""
		(layer "B.Cu")
		(at 176.779174 -76.327 180)
		(property "Reference" "R197"
			(at 0 0 0)
			(layer "B.SilkS")
			(hide yes)
			(effects
				(font
					(size 1.27 1.27)
				)
				(justify mirror)
			)
		)
		(property "Value" ""
			(at 0 0 0)
			(layer "B.Fab")
			(effects
				(font
					(size 1.27 1.27)
				)
				(justify mirror)
			)
		)
		(duplicate_pad_numbers_are_jumpers no)
		(fp_line
			(start 0.7874 0.4064)
			(end 0.7874 -0.4064)
			(stroke
				(width 0.1524)
				(type default)
			)
			(layer "B.SilkS")
		)
		(fp_line
			(start 0.7874 -0.4064)
			(end -0.7874 -0.4064)
			(stroke
				(width 0.1524)
				(type default)
			)
			(layer "B.SilkS")
		)
		(fp_line
			(start -0.7874 0.4064)
			(end 0.7874 0.4064)
			(stroke
				(width 0.1524)
				(type default)
			)
			(layer "B.SilkS")
		)
		(fp_line
			(start -0.7874 -0.4064)
			(end -0.7874 0.4064)
			(stroke
				(width 0.1524)
				(type default)
			)
			(layer "B.SilkS")
		)
		(fp_line
			(start 0.67945 0.3048)
			(end 0.67945 -0.305054)
			(stroke
				(width 0.1)
				(type default)
			)
			(layer "B.Fab")
		)
		(fp_line
			(start 0.67945 -0.305054)
			(end 0.12065 -0.305054)
			(stroke
				(width 0.1)
				(type default)
			)
			(layer "B.Fab")
		)
		(fp_line
			(start 0.12065 0.3048)
			(end 0.67945 0.3048)
			(stroke
				(width 0.1)
				(type default)
			)
			(layer "B.Fab")
		)
		(fp_line
			(start 0.12065 0.2794)
			(end 0.12065 0.3048)
			(stroke
				(width 0.1)
				(type default)
			)
			(layer "B.Fab")
		)
		(fp_line
			(start 0.12065 -0.2794)
			(end -0.12065 -0.2794)
			(stroke
				(width 0.1)
				(type default)
			)
			(layer "B.Fab")
		)
		(fp_line
			(start 0.12065 -0.305054)
			(end 0.12065 -0.2794)
			(stroke
				(width 0.1)
				(type default)
			)
			(layer "B.Fab")
		)
		(fp_line
			(start -0.120396 0.3048)
			(end -0.120396 0.2794)
			(stroke
				(width 0.1)
				(type default)
			)
			(layer "B.Fab")
		)
		(fp_line
			(start -0.120396 0.2794)
			(end 0.12065 0.2794)
			(stroke
				(width 0.1)
				(type default)
			)
			(layer "B.Fab")
		)
		(fp_line
			(start -0.12065 -0.2794)
			(end -0.12065 -0.3048)
			(stroke
				(width 0.1)
				(type default)
			)
			(layer "B.Fab")
		)
		(fp_line
			(start -0.12065 -0.3048)
			(end -0.67945 -0.3048)
			(stroke
				(width 0.1)
				(type default)
			)
			(layer "B.Fab")
		)
		(fp_line
			(start -0.67945 0.3048)
			(end -0.120396 0.3048)
			(stroke
				(width 0.1)
				(type default)
			)
			(layer "B.Fab")
		)
		(fp_line
			(start -0.67945 -0.3048)
			(end -0.67945 0.3048)
			(stroke
				(width 0.1)
				(type default)
			)
			(layer "B.Fab")
		)
		(pad "1" smd circle
			(at 0.40005 0)
			(size 0 0)
			(layers "B.Cu" "B.Mask" "B.Paste")
			(net "P12V_BRICK2_ALERT_N")
		)
		(pad "2" smd circle
			(at -0.40005 0)
			(size 0 0)
			(layers "B.Cu" "B.Mask" "B.Paste")
			(net "SMB_BRICK2_ALERT")
		)
	)
	(footprint ""
		(layer "B.Cu")
		(at 202.946 -86.614 180)
		(property "Reference" "R101"
			(at 0 0 0)
			(layer "B.SilkS")
			(hide yes)
			(effects
				(font
					(size 1.27 1.27)
				)
				(justify mirror)
			)
		)
		(property "Value" ""
			(at 0 0 0)
			(layer "B.Fab")
			(effects
				(font
					(size 1.27 1.27)
				)
				(justify mirror)
			)
		)
		(duplicate_pad_numbers_are_jumpers no)
		(fp_line
			(start 0.7874 0.4064)
			(end 0.7874 -0.4064)
			(stroke
				(width 0.1524)
				(type default)
			)
			(layer "B.SilkS")
		)
		(fp_line
			(start 0.7874 -0.4064)
			(end -0.7874 -0.4064)
			(stroke
				(width 0.1524)
				(type default)
			)
			(layer "B.SilkS")
		)
		(fp_line
			(start -0.7874 0.4064)
			(end 0.7874 0.4064)
			(stroke
				(width 0.1524)
				(type default)
			)
			(layer "B.SilkS")
		)
		(fp_line
			(start -0.7874 -0.4064)
			(end -0.7874 0.4064)
			(stroke
				(width 0.1524)
				(type default)
			)
			(layer "B.SilkS")
		)
		(fp_line
			(start 0.67945 0.3048)
			(end 0.67945 -0.305054)
			(stroke
				(width 0.1)
				(type default)
			)
			(layer "B.Fab")
		)
		(fp_line
			(start 0.67945 -0.305054)
			(end 0.12065 -0.305054)
			(stroke
				(width 0.1)
				(type default)
			)
			(layer "B.Fab")
		)
		(fp_line
			(start 0.12065 0.3048)
			(end 0.67945 0.3048)
			(stroke
				(width 0.1)
				(type default)
			)
			(layer "B.Fab")
		)
		(fp_line
			(start 0.12065 0.2794)
			(end 0.12065 0.3048)
			(stroke
				(width 0.1)
				(type default)
			)
			(layer "B.Fab")
		)
		(fp_line
			(start 0.12065 -0.2794)
			(end -0.12065 -0.2794)
			(stroke
				(width 0.1)
				(type default)
			)
			(layer "B.Fab")
		)
		(fp_line
			(start 0.12065 -0.305054)
			(end 0.12065 -0.2794)
			(stroke
				(width 0.1)
				(type default)
			)
			(layer "B.Fab")
		)
		(fp_line
			(start -0.120396 0.3048)
			(end -0.120396 0.2794)
			(stroke
				(width 0.1)
				(type default)
			)
			(layer "B.Fab")
		)
		(fp_line
			(start -0.120396 0.2794)
			(end 0.12065 0.2794)
			(stroke
				(width 0.1)
				(type default)
			)
			(layer "B.Fab")
		)
		(fp_line
			(start -0.12065 -0.2794)
			(end -0.12065 -0.3048)
			(stroke
				(width 0.1)
				(type default)
			)
			(layer "B.Fab")
		)
		(fp_line
			(start -0.12065 -0.3048)
			(end -0.67945 -0.3048)
			(stroke
				(width 0.1)
				(type default)
			)
			(layer "B.Fab")
		)
		(fp_line
			(start -0.67945 0.3048)
			(end -0.120396 0.3048)
			(stroke
				(width 0.1)
				(type default)
			)
			(layer "B.Fab")
		)
		(fp_line
			(start -0.67945 -0.3048)
			(end -0.67945 0.3048)
			(stroke
				(width 0.1)
				(type default)
			)
			(layer "B.Fab")
		)
		(pad "1" smd circle
			(at 0.40005 0)
			(size 0 0)
			(layers "B.Cu" "B.Mask" "B.Paste")
			(net "PU_9543_0_INT1")
		)
		(pad "2" smd circle
			(at -0.40005 0)
			(size 0 0)
			(layers "B.Cu" "B.Mask" "B.Paste")
			(net "P3V3_AUX")
		)
	)
	(footprint ""
		(layer "B.Cu")
		(at 275.169122 -99.695)
		(property "Reference" "PC553"
			(at 0 0 0)
			(layer "B.SilkS")
			(hide yes)
			(effects
				(font
					(size 1.27 1.27)
				)
				(justify mirror)
			)
		)
		(property "Value" ""
			(at 0 0 0)
			(layer "B.Fab")
			(effects
				(font
					(size 1.27 1.27)
				)
				(justify mirror)
			)
		)
		(duplicate_pad_numbers_are_jumpers no)
		(fp_line
			(start -1.2954 -0.5842)
			(end -1.2954 0.5842)
			(stroke
				(width 0.1524)
				(type default)
			)
			(layer "B.SilkS")
		)
		(fp_line
			(start -1.2954 0.5842)
			(end 1.2954 0.5842)
			(stroke
				(width 0.1524)
				(type default)
			)
			(layer "B.SilkS")
		)
		(fp_line
			(start 1.2954 -0.5842)
			(end -1.2954 -0.5842)
			(stroke
				(width 0.1524)
				(type default)
			)
			(layer "B.SilkS")
		)
		(fp_line
			(start 1.2954 0.5842)
			(end 1.2954 -0.5842)
			(stroke
				(width 0.1524)
				(type default)
			)
			(layer "B.SilkS")
		)
		(fp_line
			(start -1.1938 -0.4064)
			(end -1.1938 0.4064)
			(stroke
				(width 0.1)
				(type default)
			)
			(layer "B.Fab")
		)
		(fp_line
			(start -1.1938 0.4064)
			(end -0.8636 0.4064)
			(stroke
				(width 0.1)
				(type default)
			)
			(layer "B.Fab")
		)
		(fp_line
			(start -0.8636 -0.4572)
			(end -0.8636 -0.4064)
			(stroke
				(width 0.1)
				(type default)
			)
			(layer "B.Fab")
		)
		(fp_line
			(start -0.8636 -0.4064)
			(end -1.1938 -0.4064)
			(stroke
				(width 0.1)
				(type default)
			)
			(layer "B.Fab")
		)
		(fp_line
			(start -0.8636 0.4064)
			(end -0.8636 0.4572)
			(stroke
				(width 0.1)
				(type default)
			)
			(layer "B.Fab")
		)
		(fp_line
			(start -0.8636 0.4572)
			(end 0.8636 0.4572)
			(stroke
				(width 0.1)
				(type default)
			)
			(layer "B.Fab")
		)
		(fp_line
			(start 0.8636 -0.4572)
			(end -0.8636 -0.4572)
			(stroke
				(width 0.1)
				(type default)
			)
			(layer "B.Fab")
		)
		(fp_line
			(start 0.8636 -0.4064)
			(end 0.8636 -0.4572)
			(stroke
				(width 0.1)
				(type default)
			)
			(layer "B.Fab")
		)
		(fp_line
			(start 0.8636 0.4064)
			(end 1.1938 0.4064)
			(stroke
				(width 0.1)
				(type default)
			)
			(layer "B.Fab")
		)
		(fp_line
			(start 0.8636 0.4572)
			(end 0.8636 0.4064)
			(stroke
				(width 0.1)
				(type default)
			)
			(layer "B.Fab")
		)
		(fp_line
			(start 1.1938 -0.4064)
			(end 0.8636 -0.4064)
			(stroke
				(width 0.1)
				(type default)
			)
			(layer "B.Fab")
		)
		(fp_line
			(start 1.1938 0.4064)
			(end 1.1938 -0.4064)
			(stroke
				(width 0.1)
				(type default)
			)
			(layer "B.Fab")
		)
		(pad "1" smd rect
			(at 0.7366 0 270)
			(size 0.7112 0.8128)
			(layers "B.Cu" "B.Mask" "B.Paste")
			(net "P52V_HS1_GATE_RC")
		)
		(pad "2" smd rect
			(at -0.7366 0 270)
			(size 0.7112 0.8128)
			(layers "B.Cu" "B.Mask" "B.Paste")
			(net "P52V_HS")
		)
	)
)
